(kicad_pcb
	(version 20241229)
	(generator "pcbnew")
	(generator_version "9.0")
	(general
		(thickness 1.6296)
		(legacy_teardrops no)
	)
	(paper "A3")
	(title_block
		(title "Thunderbolt to 10GbE adapter")
		(date "2026-04-21")
		(rev "1.1.0")
		(company "Antmicro Ltd")
		(comment 1 "www.antmicro.com")
		(comment 9 "footprints 526-530 of 703")
	)
	(layers
		(0 "F.Cu" signal)
		(4 "In1.Cu" signal)
		(6 "In2.Cu" signal)
		(8 "In3.Cu" signal)
		(10 "In4.Cu" signal)
		(12 "In5.Cu" signal)
		(14 "In6.Cu" signal)
		(2 "B.Cu" signal)
		(9 "F.Adhes" user "F.Adhesive")
		(11 "B.Adhes" user "B.Adhesive")
		(13 "F.Paste" user)
		(15 "B.Paste" user)
		(5 "F.SilkS" user "F.Silkscreen")
		(7 "B.SilkS" user "B.Silkscreen")
		(1 "F.Mask" user)
		(3 "B.Mask" user)
		(17 "Dwgs.User" user "User.Drawings")
		(19 "Cmts.User" user "User.Comments")
		(21 "Eco1.User" user "User.Eco1")
		(23 "Eco2.User" user "User.Eco2")
		(25 "Edge.Cuts" user)
		(27 "Margin" user)
		(31 "F.CrtYd" user "F.Courtyard")
		(29 "B.CrtYd" user "B.Courtyard")
		(35 "F.Fab" user)
		(33 "B.Fab" user)
	)
	(footprint "antmicro-footprints:C_0402_1005Metric"
		(layer "B.Cu")
		(at 123.5 145.1 -90)
		(descr "Capacitor SMD 0402")
		(tags "capacitor SMD 0402")
		(property "Reference" "C1"
			(at -2.35 -0.3 90)
			(layer "B.SilkS")
			(effects
				(font
					(size 0.7 0.7)
					(thickness 0.15)
				)
				(justify left bottom mirror)
			)
		)
		(property "Value" "C_100n_0402"
			(at -1.022927 -2.155213 90)
			(layer "B.Fab")
			(effects
				(font
					(size 0.7 0.7)
					(thickness 0.15)
				)
				(justify left bottom mirror)
			)
		)
		(property "Datasheet" "https://www.murata.com/products/productdetail?partno=GRM155R61H104KE14%23"
			(at 0 0 90)
			(layer "B.Fab")
			(hide yes)
			(effects
				(font
					(size 1.27 1.27)
					(thickness 0.15)
				)
				(justify mirror)
			)
		)
		(property "Description" "SMD Multilayer Ceramic Capacitor, 0.1 µF, 50 V, 0402 [1005 Metric], ± 10%, X5R, GRM Series"
			(at 0 0 90)
			(layer "B.Fab")
			(hide yes)
			(effects
				(font
					(size 1.27 1.27)
					(thickness 0.15)
				)
				(justify mirror)
			)
		)
		(property "MPN" "GRM155R61H104KE14D"
			(at 0 0 270)
			(unlocked yes)
			(layer "B.Fab")
			(hide yes)
			(effects
				(font
					(size 1 1)
					(thickness 0.15)
				)
				(justify mirror)
			)
		)
		(property "Manufacturer" "Murata"
			(at 0 0 270)
			(unlocked yes)
			(layer "B.Fab")
			(hide yes)
			(effects
				(font
					(size 1 1)
					(thickness 0.15)
				)
				(justify mirror)
			)
		)
		(property "License" "Apache-2.0"
			(at 0 0 270)
			(unlocked yes)
			(layer "B.Fab")
			(hide yes)
			(effects
				(font
					(size 1 1)
					(thickness 0.15)
				)
				(justify mirror)
			)
		)
		(property "Author" "Antmicro"
			(at 0 0 270)
			(unlocked yes)
			(layer "B.Fab")
			(hide yes)
			(effects
				(font
					(size 1 1)
					(thickness 0.15)
				)
				(justify mirror)
			)
		)
		(property "Val" "100n"
			(at 0 0 270)
			(unlocked yes)
			(layer "B.Fab")
			(hide yes)
			(effects
				(font
					(size 1 1)
					(thickness 0.15)
				)
				(justify mirror)
			)
		)
		(property "Voltage" "50V"
			(at 0 0 270)
			(unlocked yes)
			(layer "B.Fab")
			(hide yes)
			(effects
				(font
					(size 1 1)
					(thickness 0.15)
				)
				(justify mirror)
			)
		)
		(property "Dielectric" "X5R"
			(at 0 0 270)
			(unlocked yes)
			(layer "B.Fab")
			(hide yes)
			(effects
				(font
					(size 1 1)
					(thickness 0.15)
				)
				(justify mirror)
			)
		)
		(sheetname "/USB-C connector/")
		(sheetfile "USB-C_connector.kicad_sch")
		(attr smd)
		(fp_rect
			(start -0.925 0.47)
			(end 0.925 -0.47)
			(stroke
				(width 0.05)
				(type default)
			)
			(fill no)
			(layer "B.CrtYd")
		)
		(fp_line
			(start -0.494 0.25)
			(end 0.504 0.25)
			(stroke
				(width 0.15)
				(type solid)
			)
			(layer "B.Fab")
		)
		(fp_line
			(start 0.504 0.25)
			(end 0.504 -0.248)
			(stroke
				(width 0.15)
				(type solid)
			)
			(layer "B.Fab")
		)
		(fp_line
			(start -0.494 -0.248)
			(end -0.494 0.25)
			(stroke
				(width 0.15)
				(type solid)
			)
			(layer "B.Fab")
		)
		(fp_line
			(start 0.504 -0.248)
			(end -0.494 -0.248)
			(stroke
				(width 0.15)
				(type solid)
			)
			(layer "B.Fab")
		)
		(fp_text user "${REFERENCE}"
			(at -0.939 -4.599 90)
			(layer "B.Fab")
			(effects
				(font
					(size 0.7 0.7)
					(thickness 0.15)
				)
				(justify left bottom mirror)
			)
		)
		(fp_text user "Author: Antmicro"
			(at -0.939 -3.399 90)
			(layer "B.Fab")
			(effects
				(font
					(size 0.7 0.7)
					(thickness 0.15)
				)
				(justify left bottom mirror)
			)
		)
		(fp_text user "License: Apache-2.0"
			(at -0.939 -5.799 90)
			(layer "B.Fab")
			(effects
				(font
					(size 0.7 0.7)
					(thickness 0.15)
				)
				(justify left bottom mirror)
			)
		)
		(pad "1" smd roundrect
			(at -0.48 0 270)
			(size 0.59 0.64)
			(layers "B.Cu" "B.Mask" "B.Paste")
			(roundrect_rratio 0.25)
			(net 23 "GND")
			(pintype "passive")
		)
		(pad "2" smd roundrect
			(at 0.48 0 270)
			(size 0.59 0.64)
			(layers "B.Cu" "B.Mask" "B.Paste")
			(roundrect_rratio 0.25)
			(net 215 "/USB-C connector/VBUS")
			(pintype "passive")
		)
	)
	(footprint "antmicro-footprints:C_0402_1005Metric"
		(layer "B.Cu")
		(at 133.739999 117 180)
		(descr "Capacitor SMD 0402")
		(tags "capacitor SMD 0402")
		(property "Reference" "C38"
			(at -19.525001 7.450001 0)
			(layer "B.SilkS")
			(effects
				(font
					(size 0.7 0.7)
					(thickness 0.15)
				)
				(justify mirror)
			)
		)
		(property "Value" "C_100n_0402"
			(at -1.022927 -2.155213 0)
			(layer "B.Fab")
			(effects
				(font
					(size 0.7 0.7)
					(thickness 0.15)
				)
				(justify left bottom mirror)
			)
		)
		(property "Datasheet" "https://www.murata.com/products/productdetail?partno=GRM155R61H104KE14%23"
			(at 0 0 0)
			(layer "B.Fab")
			(hide yes)
			(effects
				(font
					(size 1.27 1.27)
					(thickness 0.15)
				)
				(justify mirror)
			)
		)
		(property "Description" "SMD Multilayer Ceramic Capacitor, 0.1 µF, 50 V, 0402 [1005 Metric], ± 10%, X5R, GRM Series"
			(at 0 0 0)
			(layer "B.Fab")
			(hide yes)
			(effects
				(font
					(size 1.27 1.27)
					(thickness 0.15)
				)
				(justify mirror)
			)
		)
		(property "MPN" "GRM155R61H104KE14D"
			(at 0 0 180)
			(unlocked yes)
			(layer "B.Fab")
			(hide yes)
			(effects
				(font
					(size 1 1)
					(thickness 0.15)
				)
				(justify mirror)
			)
		)
		(property "Manufacturer" "Murata"
			(at 0 0 180)
			(unlocked yes)
			(layer "B.Fab")
			(hide yes)
			(effects
				(font
					(size 1 1)
					(thickness 0.15)
				)
				(justify mirror)
			)
		)
		(property "License" "Apache-2.0"
			(at 0 0 180)
			(unlocked yes)
			(layer "B.Fab")
			(hide yes)
			(effects
				(font
					(size 1 1)
					(thickness 0.15)
				)
				(justify mirror)
			)
		)
		(property "Val" "100n"
			(at 0 0 180)
			(unlocked yes)
			(layer "B.Fab")
			(hide yes)
			(effects
				(font
					(size 1 1)
					(thickness 0.15)
				)
				(justify mirror)
			)
		)
		(property "Voltage" "50V"
			(at 0 0 180)
			(unlocked yes)
			(layer "B.Fab")
			(hide yes)
			(effects
				(font
					(size 1 1)
					(thickness 0.15)
				)
				(justify mirror)
			)
		)
		(property "Dielectric" "X5R"
			(at 0 0 180)
			(unlocked yes)
			(layer "B.Fab")
			(hide yes)
			(effects
				(font
					(size 1 1)
					(thickness 0.15)
				)
				(justify mirror)
			)
		)
		(property "Author" "Antmicro"
			(at 0 0 180)
			(unlocked yes)
			(layer "B.Fab")
			(hide yes)
			(effects
				(font
					(size 1 1)
					(thickness 0.15)
				)
				(justify mirror)
			)
		)
		(sheetname "/TB Controller/")
		(sheetfile "tb.kicad_sch")
		(attr smd)
		(fp_rect
			(start -0.925 0.47)
			(end 0.925 -0.47)
			(stroke
				(width 0.05)
				(type default)
			)
			(fill no)
			(layer "B.CrtYd")
		)
		(fp_line
			(start 0.504 0.25)
			(end 0.504 -0.248)
			(stroke
				(width 0.15)
				(type solid)
			)
			(layer "B.Fab")
		)
		(fp_line
			(start 0.504 -0.248)
			(end -0.494 -0.248)
			(stroke
				(width 0.15)
				(type solid)
			)
			(layer "B.Fab")
		)
		(fp_line
			(start -0.494 0.25)
			(end 0.504 0.25)
			(stroke
				(width 0.15)
				(type solid)
			)
			(layer "B.Fab")
		)
		(fp_line
			(start -0.494 -0.248)
			(end -0.494 0.25)
			(stroke
				(width 0.15)
				(type solid)
			)
			(layer "B.Fab")
		)
		(fp_text user "License: Apache-2.0"
			(at -0.939 -5.799 0)
			(layer "B.Fab")
			(effects
				(font
					(size 0.7 0.7)
					(thickness 0.15)
				)
				(justify left bottom mirror)
			)
		)
		(fp_text user "Author: Antmicro"
			(at -0.939 -3.399 0)
			(layer "B.Fab")
			(effects
				(font
					(size 0.7 0.7)
					(thickness 0.15)
				)
				(justify left bottom mirror)
			)
		)
		(fp_text user "${REFERENCE}"
			(at -0.939 -4.599 0)
			(layer "B.Fab")
			(effects
				(font
					(size 0.7 0.7)
					(thickness 0.15)
				)
				(justify left bottom mirror)
			)
		)
		(pad "1" smd roundrect
			(at -0.48 0 180)
			(size 0.59 0.64)
			(layers "B.Cu" "B.Mask" "B.Paste")
			(roundrect_rratio 0.25)
			(net 79 "/PD and TB DC-DC/AUX.-")
			(pintype "passive")
		)
		(pad "2" smd roundrect
			(at 0.48 0 180)
			(size 0.59 0.64)
			(layers "B.Cu" "B.Mask" "B.Paste")
			(roundrect_rratio 0.25)
			(net 240 "/TB Controller/PA_AUX_N")
			(pintype "passive")
		)
	)
	(footprint "antmicro-footprints:R_0402_1005Metric"
		(layer "B.Cu")
		(at 147.531866 70.535117)
		(descr "Resistor SMD 0402")
		(tags "resistor SMD 0402")
		(property "Reference" "R159"
			(at 19.068134 9.464883 180)
			(layer "B.SilkS")
			(effects
				(font
					(size 0.7 0.7)
					(thickness 0.15)
				)
				(justify mirror)
			)
		)
		(property "Value" "R_10k_0402"
			(at -1.011843 -1.772047 180)
			(layer "B.Fab")
			(effects
				(font
					(size 0.7 0.7)
					(thickness 0.15)
				)
				(justify left bottom mirror)
			)
		)
		(property "Datasheet" "https://www.bourns.com/docs/product-datasheets/cr.pdf"
			(at 0 0 180)
			(layer "B.Fab")
			(hide yes)
			(effects
				(font
					(size 1.27 1.27)
					(thickness 0.15)
				)
				(justify mirror)
			)
		)
		(property "Description" "SMD Chip Resistor, 10 kohm, ± 1%, 62.5 mW, 0402 [1005 Metric], Thick Film, General Purpose"
			(at 0 0 180)
			(layer "B.Fab")
			(hide yes)
			(effects
				(font
					(size 1.27 1.27)
					(thickness 0.15)
				)
				(justify mirror)
			)
		)
		(property "MPN" "CR0402-FX-1002GLF"
			(at 0 0 0)
			(unlocked yes)
			(layer "B.Fab")
			(hide yes)
			(effects
				(font
					(size 1 1)
					(thickness 0.15)
				)
				(justify mirror)
			)
		)
		(property "Manufacturer" "Bourns"
			(at 0 0 0)
			(unlocked yes)
			(layer "B.Fab")
			(hide yes)
			(effects
				(font
					(size 1 1)
					(thickness 0.15)
				)
				(justify mirror)
			)
		)
		(property "License" "Apache-2.0"
			(at 0 0 0)
			(unlocked yes)
			(layer "B.Fab")
			(hide yes)
			(effects
				(font
					(size 1 1)
					(thickness 0.15)
				)
				(justify mirror)
			)
		)
		(property "Author" "Antmicro"
			(at 0 0 0)
			(unlocked yes)
			(layer "B.Fab")
			(hide yes)
			(effects
				(font
					(size 1 1)
					(thickness 0.15)
				)
				(justify mirror)
			)
		)
		(property "Val" "10k"
			(at 0 0 0)
			(unlocked yes)
			(layer "B.Fab")
			(hide yes)
			(effects
				(font
					(size 1 1)
					(thickness 0.15)
				)
				(justify mirror)
			)
		)
		(property "Tolerance" "1%"
			(at 0 0 0)
			(unlocked yes)
			(layer "B.Fab")
			(hide yes)
			(effects
				(font
					(size 1 1)
					(thickness 0.15)
				)
				(justify mirror)
			)
		)
		(sheetname "/X710-AT2 Misc/")
		(sheetfile "x710-at2-mics.kicad_sch")
		(attr smd)
		(fp_rect
			(start -0.925 0.47)
			(end 0.925 -0.47)
			(stroke
				(width 0.05)
				(type default)
			)
			(fill no)
			(layer "B.CrtYd")
		)
		(fp_rect
			(start -0.5 0.25)
			(end 0.5 -0.25)
			(stroke
				(width 0.15)
				(type solid)
			)
			(fill no)
			(layer "B.Fab")
		)
		(fp_text user "License: Apache-2.0"
			(at -0.95 -5.169 180)
			(layer "B.Fab")
			(effects
				(font
					(size 0.7 0.7)
					(thickness 0.15)
				)
				(justify left bottom mirror)
			)
		)
		(fp_text user "${REFERENCE}"
			(at -0.95 -3.168 180)
			(layer "B.Fab")
			(effects
				(font
					(size 0.7 0.7)
					(thickness 0.15)
				)
				(justify left bottom mirror)
			)
		)
		(fp_text user "Author: Antmicro"
			(at -0.95 -4.169 180)
			(layer "B.Fab")
			(effects
				(font
					(size 0.7 0.7)
					(thickness 0.15)
				)
				(justify left bottom mirror)
			)
		)
		(pad "1" smd roundrect
			(at -0.48 0)
			(size 0.59 0.64)
			(layers "B.Cu" "B.Mask" "B.Paste")
			(roundrect_rratio 0.25)
			(net 126 "/X710-AT2 Misc/~{PCI_DIS}")
			(pintype "passive")
		)
		(pad "2" smd roundrect
			(at 0.48 0)
			(size 0.59 0.64)
			(layers "B.Cu" "B.Mask" "B.Paste")
			(roundrect_rratio 0.25)
			(net 7 "+3V3")
			(pintype "passive")
		)
	)
	(footprint "antmicro-footprints:TP_SMD_0.75mm"
		(layer "B.Cu")
		(at 183.75 84.75 90)
		(property "Reference" "TP19"
			(at -13.25 0.75 270)
			(layer "B.SilkS")
			(effects
				(font
					(size 0.7 0.7)
					(thickness 0.15)
				)
				(justify left bottom mirror)
			)
		)
		(property "Value" "TP_0.75mm_SMD"
			(at 0 -1.2 270)
			(layer "B.Fab")
			(effects
				(font
					(size 0.7 0.7)
					(thickness 0.15)
				)
				(justify left bottom mirror)
			)
		)
		(property "Description" "SMT test point"
			(at 0 0 270)
			(layer "B.Fab")
			(hide yes)
			(effects
				(font
					(size 1.27 1.27)
					(thickness 0.15)
				)
				(justify mirror)
			)
		)
		(property "MPN" ""
			(at 0 0 90)
			(unlocked yes)
			(layer "B.Fab")
			(hide yes)
			(effects
				(font
					(size 1 1)
					(thickness 0.15)
				)
				(justify mirror)
			)
		)
		(property "Manufacturer" ""
			(at 0 0 90)
			(unlocked yes)
			(layer "B.Fab")
			(hide yes)
			(effects
				(font
					(size 1 1)
					(thickness 0.15)
				)
				(justify mirror)
			)
		)
		(property "Author" "Antmicro"
			(at 0 0 90)
			(unlocked yes)
			(layer "B.Fab")
			(hide yes)
			(effects
				(font
					(size 1 1)
					(thickness 0.15)
				)
				(justify mirror)
			)
		)
		(property "License" "Apache-2.0"
			(at 0 0 90)
			(unlocked yes)
			(layer "B.Fab")
			(hide yes)
			(effects
				(font
					(size 1 1)
					(thickness 0.15)
				)
				(justify mirror)
			)
		)
		(sheetname "/X710 DCDC converters/")
		(sheetfile "DCDC_converters_X710.kicad_sch")
		(attr exclude_from_pos_files exclude_from_bom)
		(fp_circle
			(center 0 0)
			(end 0.475 0)
			(stroke
				(width 0.05)
				(type default)
			)
			(fill no)
			(layer "B.CrtYd")
		)
		(fp_text user "${REFERENCE}"
			(at -0.4 -2.7 270)
			(layer "B.Fab")
			(effects
				(font
					(size 0.7 0.7)
					(thickness 0.15)
				)
				(justify left bottom mirror)
			)
		)
		(fp_text user "License: Apache-2.0"
			(at -0.4 -5.101 270)
			(layer "B.Fab")
			(effects
				(font
					(size 0.7 0.7)
					(thickness 0.15)
				)
				(justify left bottom mirror)
			)
		)
		(fp_text user "Author: Antmicro"
			(at -0.4 -3.901 270)
			(layer "B.Fab")
			(effects
				(font
					(size 0.7 0.7)
					(thickness 0.15)
				)
				(justify left bottom mirror)
			)
		)
		(pad "1" smd circle
			(at 0 0 90)
			(size 0.75 0.75)
			(layers "B.Cu" "B.Mask")
			(net 6 "DVDD")
			(pinfunction "1")
			(pintype "passive")
		)
	)
	(footprint "antmicro-footprints:C_0402_1005Metric"
		(layer "B.Cu")
		(at 153.031866 74.235118 180)
		(descr "Capacitor SMD 0402")
		(tags "capacitor SMD 0402")
		(property "Reference" "C248"
			(at -21.168135 -9.464883 0)
			(layer "B.SilkS")
			(effects
				(font
					(size 0.7 0.7)
					(thickness 0.15)
				)
				(justify mirror)
			)
		)
		(property "Value" "C_1u_25V_0402"
			(at -1.022927 -2.155213 0)
			(layer "B.Fab")
			(effects
				(font
					(size 0.7 0.7)
					(thickness 0.15)
				)
				(justify left bottom mirror)
			)
		)
		(property "Datasheet" "https://www.murata.com/products/productdetail?partno=GRM155R61E105KE11%23"
			(at 0 0 0)
			(layer "B.Fab")
			(hide yes)
			(effects
				(font
					(size 1.27 1.27)
					(thickness 0.15)
				)
				(justify mirror)
			)
		)
		(property "Description" "SMD Multilayer Ceramic Capacitor, 1 µF, 25 V, 0402 [1005 Metric], ± 10%, X5R, GRM Series"
			(at 0 0 0)
			(layer "B.Fab")
			(hide yes)
			(effects
				(font
					(size 1.27 1.27)
					(thickness 0.15)
				)
				(justify mirror)
			)
		)
		(property "MPN" "GRM155R61E105KE11J"
			(at 0 0 180)
			(unlocked yes)
			(layer "B.Fab")
			(hide yes)
			(effects
				(font
					(size 1 1)
					(thickness 0.15)
				)
				(justify mirror)
			)
		)
		(property "Manufacturer" "Murata"
			(at 0 0 180)
			(unlocked yes)
			(layer "B.Fab")
			(hide yes)
			(effects
				(font
					(size 1 1)
					(thickness 0.15)
				)
				(justify mirror)
			)
		)
		(property "License" "Apache-2.0"
			(at 0 0 180)
			(unlocked yes)
			(layer "B.Fab")
			(hide yes)
			(effects
				(font
					(size 1 1)
					(thickness 0.15)
				)
				(justify mirror)
			)
		)
		(property "Author" "Antmicro"
			(at 0 0 180)
			(unlocked yes)
			(layer "B.Fab")
			(hide yes)
			(effects
				(font
					(size 1 1)
					(thickness 0.15)
				)
				(justify mirror)
			)
		)
		(property "Val" "1u"
			(at 0 0 180)
			(unlocked yes)
			(layer "B.Fab")
			(hide yes)
			(effects
				(font
					(size 1 1)
					(thickness 0.15)
				)
				(justify mirror)
			)
		)
		(property "Voltage" "25V"
			(at 0 0 180)
			(unlocked yes)
			(layer "B.Fab")
			(hide yes)
			(effects
				(font
					(size 1 1)
					(thickness 0.15)
				)
				(justify mirror)
			)
		)
		(property "Dielectric" "X5R"
			(at 0 0 180)
			(unlocked yes)
			(layer "B.Fab")
			(hide yes)
			(effects
				(font
					(size 1 1)
					(thickness 0.15)
				)
				(justify mirror)
			)
		)
		(sheetname "/X710-AT2 power/")
		(sheetfile "x710-at2-power.kicad_sch")
		(attr smd)
		(fp_rect
			(start -0.925 0.47)
			(end 0.925 -0.47)
			(stroke
				(width 0.05)
				(type default)
			)
			(fill no)
			(layer "B.CrtYd")
		)
		(fp_line
			(start 0.504 0.25)
			(end 0.504 -0.248)
			(stroke
				(width 0.15)
				(type solid)
			)
			(layer "B.Fab")
		)
		(fp_line
			(start 0.504 -0.248)
			(end -0.494 -0.248)
			(stroke
				(width 0.15)
				(type solid)
			)
			(layer "B.Fab")
		)
		(fp_line
			(start -0.494 0.25)
			(end 0.504 0.25)
			(stroke
				(width 0.15)
				(type solid)
			)
			(layer "B.Fab")
		)
		(fp_line
			(start -0.494 -0.248)
			(end -0.494 0.25)
			(stroke
				(width 0.15)
				(type solid)
			)
			(layer "B.Fab")
		)
		(fp_text user "Author: Antmicro"
			(at -0.939 -3.399 0)
			(layer "B.Fab")
			(effects
				(font
					(size 0.7 0.7)
					(thickness 0.15)
				)
				(justify left bottom mirror)
			)
		)
		(fp_text user "${REFERENCE}"
			(at -0.939 -4.599 0)
			(layer "B.Fab")
			(effects
				(font
					(size 0.7 0.7)
					(thickness 0.15)
				)
				(justify left bottom mirror)
			)
		)
		(fp_text user "License: Apache-2.0"
			(at -0.939 -5.799 0)
			(layer "B.Fab")
			(effects
				(font
					(size 0.7 0.7)
					(thickness 0.15)
				)
				(justify left bottom mirror)
			)
		)
		(pad "1" smd roundrect
			(at -0.48 0 180)
			(size 0.59 0.64)
			(layers "B.Cu" "B.Mask" "B.Paste")
			(roundrect_rratio 0.25)
			(net 23 "GND")
			(pintype "passive")
		)
		(pad "2" smd roundrect
			(at 0.48 0 180)
			(size 0.59 0.64)
			(layers "B.Cu" "B.Mask" "B.Paste")
			(roundrect_rratio 0.25)
			(net 7 "+3V3")
			(pintype "passive")
		)
	)
)
